(kicad_pcb
	(version 20260206)
	(generator "pcbnew")
	(generator_version "10.0")
	(general
		(thickness 1.6)
		(legacy_teardrops no)
	)
	(paper "A4")
	(title_block
		(title "timecard-production-celestica-r4006 — R4006-B0001-02_R01.brd")
		(comment 1 "Time Appliance Project (Time Card) / footprints 631-636 of 1113")
	)
	(layers
		(0 "F.Cu" signal "TOP")
		(4 "In1.Cu" signal "L02_GND1")
		(6 "In2.Cu" signal "L03_SIG1")
		(8 "In3.Cu" signal "L04_GND2")
		(10 "In4.Cu" signal "L05_VCC1")
		(12 "In5.Cu" signal "L06_VCC2")
		(14 "In6.Cu" signal "L07_GND3")
		(16 "In7.Cu" signal "L08_SIG2")
		(18 "In8.Cu" signal "L09_GND4")
		(2 "B.Cu" signal "BOTTOM")
		(9 "F.Adhes" user "F.Adhesive")
		(11 "B.Adhes" user "B.Adhesive")
		(13 "F.Paste" user "Package Geometry/Pastemask Top")
		(15 "B.Paste" user "Package Geometry/Pastemask Bottom")
		(5 "F.SilkS" user "Ref Des/Silkscreen Top")
		(7 "B.SilkS" user "Ref Des/Silkscreen Bottom")
		(1 "F.Mask" user "Board Geometry/Soldermask Top")
		(3 "B.Mask" user "Board Geometry/Soldermask Bottom")
		(17 "Dwgs.User" user "User.Drawings")
		(19 "Cmts.User" user "User.Comments")
		(21 "Eco1.User" user "User.Eco1")
		(23 "Eco2.User" user "User.Eco2")
		(25 "Edge.Cuts" user "Board Geometry/Outline")
		(27 "Margin" user)
		(31 "F.CrtYd" user "Package Geometry/Place Bound Top")
		(29 "B.CrtYd" user "Package Geometry/Place Bound Bottom")
		(35 "F.Fab" user "Ref Des/Assembly Top")
		(33 "B.Fab" user "Ref Des/Assembly Bottom")
	)
	(footprint ""
		(layer "F.Cu")
		(at 23.622 -69.2912)
		(property "Reference" "C277"
			(at 3.302 -0.13843 0)
			(unlocked yes)
			(layer "F.SilkS")
			(effects
				(font
					(size 0.7874 0.5842)
					(thickness 0.1524)
				)
			)
		)
		(property "Value" "VAL*"
			(at 0.0762 2.067306 0)
			(unlocked yes)
			(layer "F.Fab")
			(hide yes)
			(effects
				(font
					(size 0.7874 0.5842)
					(thickness 0.1524)
				)
			)
		)
		(property "Tolerance" "TOL*"
			(at 0.0762 3.032506 0)
			(unlocked yes)
			(layer "Cmts.User")
			(hide yes)
			(effects
				(font
					(size 0.7874 0.5842)
					(thickness 0.1524)
				)
			)
		)
		(property "User Part Number" "PARTNUM*"
			(at 0.1016 4.023106 0)
			(unlocked yes)
			(layer "Cmts.User")
			(hide yes)
			(effects
				(font
					(size 0.7874 0.5842)
					(thickness 0.1524)
				)
			)
		)
		(property "Device Type" "CAPACITOR-G105-0C106-BM,10UF,2A"
			(at 0.0508 1.127506 0)
			(unlocked yes)
			(layer "F.Fab")
			(hide yes)
			(effects
				(font
					(size 0.7874 0.5842)
					(thickness 0.1524)
				)
			)
		)
		(duplicate_pad_numbers_are_jumpers no)
		(fp_line
			(start -1.143 -0.5588)
			(end -1.143 0.5588)
			(stroke
				(width 0.1)
				(type default)
			)
			(layer "F.SilkS")
		)
		(fp_line
			(start -1.143 0.5588)
			(end 1.143 0.5588)
			(stroke
				(width 0.1)
				(type default)
			)
			(layer "F.SilkS")
		)
		(fp_line
			(start 1.143 -0.5588)
			(end -1.143 -0.5588)
			(stroke
				(width 0.1)
				(type default)
			)
			(layer "F.SilkS")
		)
		(fp_line
			(start 1.143 0.5588)
			(end 1.143 -0.5588)
			(stroke
				(width 0.1)
				(type default)
			)
			(layer "F.SilkS")
		)
		(fp_poly
			(pts
				(xy -1.143 -0.5588) (xy -1.143 0.5588) (xy 1.143 0.5588) (xy 1.143 -0.5588)
			)
			(stroke
				(width 0)
				(type default)
			)
			(fill no)
			(layer "F.CrtYd")
		)
		(fp_line
			(start -0.508 -0.3048)
			(end -0.508 0.3048)
			(stroke
				(width 0.1)
				(type default)
			)
			(layer "F.Fab")
		)
		(fp_line
			(start -0.508 0.3048)
			(end 0.508 0.3048)
			(stroke
				(width 0.1)
				(type default)
			)
			(layer "F.Fab")
		)
		(fp_line
			(start 0.508 -0.3048)
			(end -0.508 -0.3048)
			(stroke
				(width 0.1)
				(type default)
			)
			(layer "F.Fab")
		)
		(fp_line
			(start 0.508 0.3048)
			(end 0.508 -0.3048)
			(stroke
				(width 0.1)
				(type default)
			)
			(layer "F.Fab")
		)
		(pad "1" smd rect
			(at -0.5334 0)
			(size 0.7112 0.6096)
			(layers "F.Cu" "F.Mask" "F.Paste")
			(net "XP1R8V_ICP10100")
		)
		(pad "2" smd rect
			(at 0.5334 0)
			(size 0.7112 0.6096)
			(layers "F.Cu" "F.Mask" "F.Paste")
			(net "SG")
		)
		(zone
			(layer "F.Cu")
			(hatch none 0.5)
			(connect_pads
				(clearance 0)
			)
			(min_thickness 0.25)
			(keepout
				(tracks allowed)
				(vias not_allowed)
				(pads allowed)
				(copperpour not_allowed)
				(footprints allowed)
			)
			(placement
				(enabled no)
				(sheetname "")
			)
			(fill
				(thermal_gap 0.5)
				(thermal_bridge_width 0.5)
				(island_removal_mode 0)
			)
			(polygon
				(pts
					(xy 23.5458 -69.596) (xy 23.5458 -68.9864) (xy 23.6982 -68.9864) (xy 23.6982 -69.596)
				)
			)
		)
	)
	(footprint ""
		(layer "F.Cu")
		(at 144.050004 -107.849924 -90)
		(property "Reference" "DS3"
			(at 0.534924 1.448054 90)
			(unlocked yes)
			(layer "F.SilkS")
			(effects
				(font
					(size 0.635 0.4064)
					(thickness 0.1524)
				)
			)
		)
		(property "Value" ""
			(at 0 0 270)
			(layer "F.Fab")
			(effects
				(font
					(size 1.27 1.27)
				)
			)
		)
		(property "User Part Number" "PARTNUM*"
			(at 0.1778 2.422881 270)
			(unlocked yes)
			(layer "Cmts.User")
			(hide yes)
			(effects
				(font
					(size 0.786892 0.583946)
					(thickness 0.000001)
				)
			)
		)
		(property "Device Type" "OPTICAL-G170-10143-01"
			(at 0.1778 1.483081 270)
			(unlocked yes)
			(layer "F.Fab")
			(hide yes)
			(effects
				(font
					(size 0.786892 0.583946)
					(thickness 0.000001)
				)
			)
		)
		(duplicate_pad_numbers_are_jumpers no)
		(fp_line
			(start -1.3208 1.2192)
			(end -2.5908 1.2192)
			(stroke
				(width 0.1)
				(type default)
			)
			(layer "F.SilkS")
		)
		(fp_line
			(start -1.397508 0.704088)
			(end -1.397508 -0.704088)
			(stroke
				(width 0.1)
				(type default)
			)
			(layer "F.SilkS")
		)
		(fp_line
			(start 1.397508 0.704088)
			(end -1.397508 0.704088)
			(stroke
				(width 0.1)
				(type default)
			)
			(layer "F.SilkS")
		)
		(fp_line
			(start -1.9558 0.5842)
			(end -1.9558 1.8542)
			(stroke
				(width 0.1)
				(type default)
			)
			(layer "F.SilkS")
		)
		(fp_line
			(start -1.397508 -0.704088)
			(end 1.397508 -0.704088)
			(stroke
				(width 0.1)
				(type default)
			)
			(layer "F.SilkS")
		)
		(fp_line
			(start 1.397508 -0.704088)
			(end 1.397508 0.704088)
			(stroke
				(width 0.1)
				(type default)
			)
			(layer "F.SilkS")
		)
		(fp_rect
			(start 1.905508 0.704088)
			(end 1.397508 -0.704088)
			(stroke
				(width 0)
				(type default)
			)
			(fill yes)
			(layer "F.SilkS")
		)
		(fp_rect
			(start 1.905508 0.958088)
			(end -1.651508 -0.958088)
			(stroke
				(width 0)
				(type default)
			)
			(fill no)
			(layer "F.CrtYd")
		)
		(fp_line
			(start -1.3208 0.9652)
			(end -2.5908 0.9652)
			(stroke
				(width 0.1)
				(type default)
			)
			(layer "F.Fab")
		)
		(fp_line
			(start -0.850138 0.450088)
			(end 0.850138 0.450088)
			(stroke
				(width 0.1)
				(type default)
			)
			(layer "F.Fab")
		)
		(fp_line
			(start 0.850138 0.450088)
			(end 0.850138 -0.450088)
			(stroke
				(width 0.1)
				(type default)
			)
			(layer "F.Fab")
		)
		(fp_line
			(start -1.9558 0.3302)
			(end -1.9558 1.6002)
			(stroke
				(width 0.1)
				(type default)
			)
			(layer "F.Fab")
		)
		(fp_line
			(start -0.850138 -0.450088)
			(end -0.850138 0.450088)
			(stroke
				(width 0.1)
				(type default)
			)
			(layer "F.Fab")
		)
		(fp_line
			(start 0.850138 -0.450088)
			(end -0.850138 -0.450088)
			(stroke
				(width 0.1)
				(type default)
			)
			(layer "F.Fab")
		)
		(fp_rect
			(start 0.850138 0.450088)
			(end 0.342138 -0.450088)
			(stroke
				(width 0)
				(type default)
			)
			(fill yes)
			(layer "F.Fab")
		)
		(fp_text user "A"
			(at -1.973326 -0.729996 0)
			(unlocked yes)
			(layer "F.SilkS")
			(effects
				(font
					(size 0.635 0.4064)
					(thickness 0.1524)
				)
			)
		)
		(fp_text user "C"
			(at 1.201674 -1.237996 0)
			(unlocked yes)
			(layer "F.SilkS")
			(effects
				(font
					(size 0.635 0.4064)
					(thickness 0.1524)
				)
			)
		)
		(fp_text user "A"
			(at -1.838706 -0.094996 0)
			(unlocked yes)
			(layer "F.Fab")
			(effects
				(font
					(size 0.7874 0.5842)
					(thickness 0.1524)
				)
			)
		)
		(fp_text user "C"
			(at 0.955294 -0.983996 0)
			(unlocked yes)
			(layer "F.Fab")
			(effects
				(font
					(size 0.7874 0.5842)
					(thickness 0.1524)
				)
			)
		)
		(pad "A" smd rect
			(at -0.749808 0 270)
			(size 0.7874 0.7874)
			(layers "F.Cu" "F.Mask" "F.Paste")
			(net "UNNAMED_14_OPTICAL_I136_A")
		)
		(pad "C" smd rect
			(at 0.749808 0 270)
			(size 0.7874 0.7874)
			(layers "F.Cu" "F.Mask" "F.Paste")
			(net "LED_DATOUT1")
		)
	)
	(footprint ""
		(layer "F.Cu")
		(at 65.000124 -104.650032)
		(property "Reference" "ME1"
			(at -0.801624 4.359402 0)
			(unlocked yes)
			(layer "F.SilkS")
			(effects
				(font
					(size 0.7874 0.5842)
					(thickness 0.1524)
				)
				(justify left)
			)
		)
		(property "Value" ""
			(at 0 0 0)
			(layer "F.Fab")
			(effects
				(font
					(size 1.27 1.27)
				)
			)
		)
		(property "User Part Number" "PARTNUM*"
			(at -3.048 5.242306 0)
			(unlocked yes)
			(layer "Cmts.User")
			(hide yes)
			(effects
				(font
					(size 0.7874 0.5842)
					(thickness 0.1524)
				)
				(justify left)
			)
		)
		(property "Device Type" "NUT-G340-10437-01"
			(at -1.4732 4.226306 0)
			(unlocked yes)
			(layer "F.Fab")
			(hide yes)
			(effects
				(font
					(size 0.7874 0.5842)
					(thickness 0.1524)
				)
				(justify left)
			)
		)
		(duplicate_pad_numbers_are_jumpers no)
		(fp_circle
			(center 0 0)
			(end 3.3528 0)
			(stroke
				(width 0.1)
				(type default)
			)
			(fill no)
			(layer "F.SilkS")
		)
		(fp_poly
			(pts
				(arc
					(start -2.102612 -0.1524)
					(mid -1.490671 -1.490671)
					(end -0.1524 -2.102612)
				)
				(arc
					(start -0.1524 -3.171444)
					(mid -2.245137 -2.245137)
					(end -3.171444 -0.1524)
				)
			)
			(stroke
				(width 0)
				(type default)
			)
			(fill yes)
			(layer "F.Paste")
		)
		(fp_poly
			(pts
				(arc
					(start -0.1524 2.102612)
					(mid -1.490671 1.490671)
					(end -2.102612 0.1524)
				)
				(arc
					(start -3.171444 0.1524)
					(mid -2.245137 2.245137)
					(end -0.1524 3.171444)
				)
			)
			(stroke
				(width 0)
				(type default)
			)
			(fill yes)
			(layer "F.Paste")
		)
		(fp_poly
			(pts
				(arc
					(start 0.1524 -2.102612)
					(mid 1.490671 -1.490671)
					(end 2.102612 -0.1524)
				)
				(arc
					(start 3.171444 -0.1524)
					(mid 2.245137 -2.245137)
					(end 0.1524 -3.171444)
				)
			)
			(stroke
				(width 0)
				(type default)
			)
			(fill yes)
			(layer "F.Paste")
		)
		(fp_poly
			(pts
				(arc
					(start 2.102612 0.1524)
					(mid 1.490671 1.490671)
					(end 0.1524 2.102612)
				)
				(arc
					(start 0.1524 3.171444)
					(mid 2.245137 2.245137)
					(end 3.171444 0.1524)
				)
			)
			(stroke
				(width 0)
				(type default)
			)
			(fill yes)
			(layer "F.Paste")
		)
		(fp_rect
			(start -7.5946 7.5946)
			(end 7.5946 -7.5946)
			(stroke
				(width 0)
				(type default)
			)
			(fill no)
			(layer "B.CrtYd")
		)
		(fp_poly
			(pts
				(arc
					(start 3.6068 0)
					(mid -3.6068 0)
					(end 3.6068 0)
				)
			)
			(stroke
				(width 0)
				(type default)
			)
			(fill no)
			(layer "F.CrtYd")
		)
		(fp_circle
			(center 0 0)
			(end 2.8448 0)
			(stroke
				(width 0.1)
				(type default)
			)
			(fill no)
			(layer "F.Fab")
		)
		(pad "1" thru_hole circle
			(at 0 0)
			(size 6.1976 6.1976)
			(drill 4.2164)
			(layers "*.Cu" "*.Mask")
			(remove_unused_layers no)
			(net "SG")
			(padstack
				(mode front_inner_back)
				(layer "Inner"
					(shape circle)
					(size 5.0292 5.0292)
					(clearance -0.1143)
				)
				(layer "B.Cu"
					(shape circle)
					(size 5.0292 5.0292)
				)
			)
		)
	)
	(footprint ""
		(layer "F.Cu")
		(at 144.145 -60.96)
		(property "Reference" "R254"
			(at -2.286 -3.51663 0)
			(unlocked yes)
			(layer "F.SilkS")
			(effects
				(font
					(size 0.7874 0.5842)
					(thickness 0.1524)
				)
			)
		)
		(property "Value" "VAL*"
			(at 0.02032 2.13233 0)
			(unlocked yes)
			(layer "F.Fab")
			(hide yes)
			(effects
				(font
					(size 0.7874 0.5842)
					(thickness 0.1524)
				)
			)
		)
		(property "Device Type" "RESISTOR-G155-120R0-01,20OHM,1%"
			(at 0.008382 1.210564 0)
			(unlocked yes)
			(layer "F.Fab")
			(hide yes)
			(effects
				(font
					(size 0.7874 0.5842)
					(thickness 0.1524)
				)
			)
		)
		(property "User Part Number" "PARTNUM*"
			(at 0.02032 4.024884 0)
			(unlocked yes)
			(layer "Cmts.User")
			(hide yes)
			(effects
				(font
					(size 0.7874 0.5842)
					(thickness 0.1524)
				)
			)
		)
		(property "Tolerance" "TOL*"
			(at 0.044704 3.05435 0)
			(unlocked yes)
			(layer "Cmts.User")
			(hide yes)
			(effects
				(font
					(size 0.7874 0.5842)
					(thickness 0.1524)
				)
			)
		)
		(duplicate_pad_numbers_are_jumpers no)
		(fp_line
			(start -1.143 -0.5588)
			(end -1.143 0.5588)
			(stroke
				(width 0.1)
				(type default)
			)
			(layer "F.SilkS")
		)
		(fp_line
			(start -1.143 0.5588)
			(end 1.143 0.5588)
			(stroke
				(width 0.1)
				(type default)
			)
			(layer "F.SilkS")
		)
		(fp_line
			(start 1.143 -0.5588)
			(end -1.143 -0.5588)
			(stroke
				(width 0.1)
				(type default)
			)
			(layer "F.SilkS")
		)
		(fp_line
			(start 1.143 0.5588)
			(end 1.143 -0.5588)
			(stroke
				(width 0.1)
				(type default)
			)
			(layer "F.SilkS")
		)
		(fp_rect
			(start 1.143 -0.5588)
			(end -1.143 0.5588)
			(stroke
				(width 0)
				(type default)
			)
			(fill no)
			(layer "F.CrtYd")
		)
		(fp_line
			(start -0.508 -0.3048)
			(end -0.508 0.3048)
			(stroke
				(width 0.1)
				(type default)
			)
			(layer "F.Fab")
		)
		(fp_line
			(start -0.508 0.3048)
			(end 0.508 0.3048)
			(stroke
				(width 0.1)
				(type default)
			)
			(layer "F.Fab")
		)
		(fp_line
			(start 0.508 -0.3048)
			(end -0.508 -0.3048)
			(stroke
				(width 0.1)
				(type default)
			)
			(layer "F.Fab")
		)
		(fp_line
			(start 0.508 0.3048)
			(end 0.508 -0.3048)
			(stroke
				(width 0.1)
				(type default)
			)
			(layer "F.Fab")
		)
		(pad "1" smd rect
			(at -0.5334 0)
			(size 0.7112 0.6096)
			(layers "F.Cu" "F.Mask" "F.Paste")
			(net "XP1R0V_FPGA")
		)
		(pad "2" smd rect
			(at 0.5334 0)
			(size 0.7112 0.6096)
			(layers "F.Cu" "F.Mask" "F.Paste")
			(net "UNNAMED_523_CAPACITOR_I28_1")
		)
		(zone
			(layer "F.Cu")
			(hatch none 0.5)
			(connect_pads
				(clearance 0)
			)
			(min_thickness 0.25)
			(keepout
				(tracks allowed)
				(vias not_allowed)
				(pads allowed)
				(copperpour not_allowed)
				(footprints allowed)
			)
			(placement
				(enabled no)
				(sheetname "")
			)
			(fill
				(thermal_gap 0.5)
				(thermal_bridge_width 0.5)
				(island_removal_mode 0)
			)
			(polygon
				(pts
					(xy 144.2212 -61.2648) (xy 144.0688 -61.2648) (xy 144.0688 -60.6552) (xy 144.2212 -60.6552)
				)
			)
		)
	)
	(footprint ""
		(layer "F.Cu")
		(at 80.772 -54.9656 180)
		(property "Reference" "R302"
			(at 10.16 18.78203 0)
			(unlocked yes)
			(layer "F.SilkS")
			(effects
				(font
					(size 0.7874 0.5842)
					(thickness 0.1524)
				)
			)
		)
		(property "Value" "VAL*"
			(at 0.02032 2.13233 180)
			(unlocked yes)
			(layer "F.Fab")
			(hide yes)
			(effects
				(font
					(size 0.7874 0.5842)
					(thickness 0.1524)
				)
			)
		)
		(property "Tolerance" "TOL*"
			(at 0.044704 3.05435 180)
			(unlocked yes)
			(layer "Cmts.User")
			(hide yes)
			(effects
				(font
					(size 0.7874 0.5842)
					(thickness 0.1524)
				)
			)
		)
		(property "User Part Number" "PARTNUM*"
			(at 0.02032 4.024884 180)
			(unlocked yes)
			(layer "Cmts.User")
			(hide yes)
			(effects
				(font
					(size 0.7874 0.5842)
					(thickness 0.1524)
				)
			)
		)
		(property "Device Type" "RESISTOR-G155-11001-01,1KOHM,1%"
			(at 0.008382 1.210564 180)
			(unlocked yes)
			(layer "F.Fab")
			(hide yes)
			(effects
				(font
					(size 0.7874 0.5842)
					(thickness 0.1524)
				)
			)
		)
		(duplicate_pad_numbers_are_jumpers no)
		(fp_line
			(start 1.143 0.5588)
			(end 1.143 -0.5588)
			(stroke
				(width 0.1)
				(type default)
			)
			(layer "F.SilkS")
		)
		(fp_line
			(start 1.143 -0.5588)
			(end -1.143 -0.5588)
			(stroke
				(width 0.1)
				(type default)
			)
			(layer "F.SilkS")
		)
		(fp_line
			(start -1.143 0.5588)
			(end 1.143 0.5588)
			(stroke
				(width 0.1)
				(type default)
			)
			(layer "F.SilkS")
		)
		(fp_line
			(start -1.143 -0.5588)
			(end -1.143 0.5588)
			(stroke
				(width 0.1)
				(type default)
			)
			(layer "F.SilkS")
		)
		(fp_rect
			(start 1.143 0.5588)
			(end -1.143 -0.5588)
			(stroke
				(width 0)
				(type default)
			)
			(fill no)
			(layer "F.CrtYd")
		)
		(fp_line
			(start 0.508 0.3048)
			(end 0.508 -0.3048)
			(stroke
				(width 0.1)
				(type default)
			)
			(layer "F.Fab")
		)
		(fp_line
			(start 0.508 -0.3048)
			(end -0.508 -0.3048)
			(stroke
				(width 0.1)
				(type default)
			)
			(layer "F.Fab")
		)
		(fp_line
			(start -0.508 0.3048)
			(end 0.508 0.3048)
			(stroke
				(width 0.1)
				(type default)
			)
			(layer "F.Fab")
		)
		(fp_line
			(start -0.508 -0.3048)
			(end -0.508 0.3048)
			(stroke
				(width 0.1)
				(type default)
			)
			(layer "F.Fab")
		)
		(pad "1" smd rect
			(at -0.5334 0 180)
			(size 0.7112 0.6096)
			(layers "F.Cu" "F.Mask" "F.Paste")
			(net "BNO080_SA0")
		)
		(pad "2" smd rect
			(at 0.5334 0 180)
			(size 0.7112 0.6096)
			(layers "F.Cu" "F.Mask" "F.Paste")
			(net "SG")
		)
		(zone
			(layer "F.Cu")
			(hatch none 0.5)
			(connect_pads
				(clearance 0)
			)
			(min_thickness 0.25)
			(keepout
				(tracks allowed)
				(vias not_allowed)
				(pads allowed)
				(copperpour not_allowed)
				(footprints allowed)
			)
			(placement
				(enabled no)
				(sheetname "")
			)
			(fill
				(thermal_gap 0.5)
				(thermal_bridge_width 0.5)
				(island_removal_mode 0)
			)
			(polygon
				(pts
					(xy 80.6958 -55.2704) (xy 80.6958 -54.6608) (xy 80.8482 -54.6608) (xy 80.8482 -55.2704)
				)
			)
		)
	)
	(footprint ""
		(layer "F.Cu")
		(at 46.736 -123.825)
		(property "Reference" "SP24"
			(at 0 0 0)
			(layer "F.SilkS")
			(hide yes)
			(effects
				(font
					(size 1.27 1.27)
				)
			)
		)
		(property "Value" ""
			(at 0 0 0)
			(layer "F.Fab")
			(effects
				(font
					(size 1.27 1.27)
				)
			)
		)
		(duplicate_pad_numbers_are_jumpers no)
	)
)
